# T6G (Grand Teton) — schematic netlist excerpt (pin names and nets, part order shuffled) for the footprints in the layout excerpt that follows; sources: Cadence DE-HDL packaged netlist, KiCad conversion of 04192023_DAF0TMB3IC0_F0TG_MB_C_brd_V02_OCP.brd

R166  Q_RES  33 5% CHIP  pkg 0402LF  page 80 : A = FM_I3C_CPU0_MUX1_R_SEL ; B = FM_I3C_CPU0_MUX1_SEL
R3321  Q_RES  100K 1% CHIP  pkg 0402LF  page 127 : A = P3V3_AUX ; B = GPU_FPGA_READY_ISO
C449  Q_CAP  0.1UF 10V 10% X7S  pkg C0201  page 356 : A = P0V9_CPU1_RT_2D ; B = GND

(kicad_pcb
	(version 20260206)
	(generator "pcbnew")
	(generator_version "10.0")
	(general
		(thickness 1.6)
		(legacy_teardrops no)
	)
	(paper "A4")
	(title_block
		(title "04192023_DAF0TMB3IC0_F0TG_MB_C_brd_V02_OCP.brd")
		(comment 1 "Grand Teton / footprints 5551-5553 of 8354")
	)
	(layers
		(0 "F.Cu" signal "TOP")
		(4 "In1.Cu" signal "GND")
		(6 "In2.Cu" signal "IN1")
		(8 "In3.Cu" signal "GND1")
		(10 "In4.Cu" signal "IN2")
		(12 "In5.Cu" signal "GND2")
		(14 "In6.Cu" signal "IN3")
		(16 "In7.Cu" signal "GND3")
		(18 "In8.Cu" signal "VCC")
		(20 "In9.Cu" signal "VCC1")
		(22 "In10.Cu" signal "GND4")
		(24 "In11.Cu" signal "IN4")
		(26 "In12.Cu" signal "GND5")
		(28 "In13.Cu" signal "IN5")
		(30 "In14.Cu" signal "GND6")
		(32 "In15.Cu" signal "IN6")
		(34 "In16.Cu" signal "GND7")
		(2 "B.Cu" signal "BOTTOM")
		(9 "F.Adhes" user "F.Adhesive")
		(11 "B.Adhes" user "B.Adhesive")
		(13 "F.Paste" user "Package Geometry/Pastemask Top")
		(15 "B.Paste" user "Package Geometry/Pastemask Bottom")
		(5 "F.SilkS" user "Ref Des/Silkscreen Top")
		(7 "B.SilkS" user "Ref Des/Silkscreen Bottom")
		(1 "F.Mask" user "Board Geometry/Soldermask Top")
		(3 "B.Mask" user "Board Geometry/Soldermask Bottom")
		(17 "Dwgs.User" user "User.Drawings")
		(19 "Cmts.User" user "User.Comments")
		(21 "Eco1.User" user "User.Eco1")
		(23 "Eco2.User" user "User.Eco2")
		(25 "Edge.Cuts" user "Board Geometry/Outline")
		(27 "Margin" user)
		(31 "F.CrtYd" user "Package Geometry/Place Bound Top")
		(29 "B.CrtYd" user "Package Geometry/Place Bound Bottom")
		(35 "F.Fab" user "Ref Des/Assembly Top")
		(33 "B.Fab" user "Ref Des/Assembly Bottom")
	)
	(footprint ""
		(layer "B.Cu")
		(at 171.196 -112.232948)
		(property "Reference" "R166"
			(at 0 0 0)
			(layer "B.SilkS")
			(hide yes)
			(effects
				(font
					(size 1.27 1.27)
				)
				(justify mirror)
			)
		)
		(property "Value" ""
			(at 0 0 0)
			(layer "B.Fab")
			(effects
				(font
					(size 1.27 1.27)
				)
				(justify mirror)
			)
		)
		(duplicate_pad_numbers_are_jumpers no)
		(fp_line
			(start -0.7874 -0.4064)
			(end -0.7874 0.4064)
			(stroke
				(width 0.1524)
				(type default)
			)
			(layer "B.SilkS")
		)
		(fp_line
			(start -0.7874 0.4064)
			(end 0.7874 0.4064)
			(stroke
				(width 0.1524)
				(type default)
			)
			(layer "B.SilkS")
		)
		(fp_line
			(start 0.7874 -0.4064)
			(end -0.7874 -0.4064)
			(stroke
				(width 0.1524)
				(type default)
			)
			(layer "B.SilkS")
		)
		(fp_line
			(start 0.7874 0.4064)
			(end 0.7874 -0.4064)
			(stroke
				(width 0.1524)
				(type default)
			)
			(layer "B.SilkS")
		)
		(fp_line
			(start -0.67945 -0.3048)
			(end -0.67945 0.3048)
			(stroke
				(width 0.1)
				(type default)
			)
			(layer "B.Fab")
		)
		(fp_line
			(start -0.67945 0.3048)
			(end -0.120396 0.3048)
			(stroke
				(width 0.1)
				(type default)
			)
			(layer "B.Fab")
		)
		(fp_line
			(start -0.12065 -0.3048)
			(end -0.67945 -0.3048)
			(stroke
				(width 0.1)
				(type default)
			)
			(layer "B.Fab")
		)
		(fp_line
			(start -0.12065 -0.2794)
			(end -0.12065 -0.3048)
			(stroke
				(width 0.1)
				(type default)
			)
			(layer "B.Fab")
		)
		(fp_line
			(start -0.120396 0.2794)
			(end 0.12065 0.2794)
			(stroke
				(width 0.1)
				(type default)
			)
			(layer "B.Fab")
		)
		(fp_line
			(start -0.120396 0.3048)
			(end -0.120396 0.2794)
			(stroke
				(width 0.1)
				(type default)
			)
			(layer "B.Fab")
		)
		(fp_line
			(start 0.12065 -0.305054)
			(end 0.12065 -0.2794)
			(stroke
				(width 0.1)
				(type default)
			)
			(layer "B.Fab")
		)
		(fp_line
			(start 0.12065 -0.2794)
			(end -0.12065 -0.2794)
			(stroke
				(width 0.1)
				(type default)
			)
			(layer "B.Fab")
		)
		(fp_line
			(start 0.12065 0.2794)
			(end 0.12065 0.3048)
			(stroke
				(width 0.1)
				(type default)
			)
			(layer "B.Fab")
		)
		(fp_line
			(start 0.12065 0.3048)
			(end 0.67945 0.3048)
			(stroke
				(width 0.1)
				(type default)
			)
			(layer "B.Fab")
		)
		(fp_line
			(start 0.67945 -0.305054)
			(end 0.12065 -0.305054)
			(stroke
				(width 0.1)
				(type default)
			)
			(layer "B.Fab")
		)
		(fp_line
			(start 0.67945 0.3048)
			(end 0.67945 -0.305054)
			(stroke
				(width 0.1)
				(type default)
			)
			(layer "B.Fab")
		)
		(pad "1" smd circle
			(at 0.40005 0 180)
			(size 0 0)
			(layers "B.Cu" "B.Mask" "B.Paste")
			(net "FM_I3C_CPU0_MUX1_R_SEL")
		)
		(pad "2" smd circle
			(at -0.40005 0 180)
			(size 0 0)
			(layers "B.Cu" "B.Mask" "B.Paste")
			(net "FM_I3C_CPU0_MUX1_SEL")
		)
	)
	(footprint ""
		(layer "B.Cu")
		(at 53.151532 -421.180768)
		(property "Reference" "R3321"
			(at 0 0 0)
			(layer "B.SilkS")
			(hide yes)
			(effects
				(font
					(size 1.27 1.27)
				)
				(justify mirror)
			)
		)
		(property "Value" ""
			(at 0 0 0)
			(layer "B.Fab")
			(effects
				(font
					(size 1.27 1.27)
				)
				(justify mirror)
			)
		)
		(duplicate_pad_numbers_are_jumpers no)
		(fp_line
			(start -0.7874 -0.4064)
			(end -0.7874 0.4064)
			(stroke
				(width 0.1524)
				(type default)
			)
			(layer "B.SilkS")
		)
		(fp_line
			(start -0.7874 0.4064)
			(end 0.7874 0.4064)
			(stroke
				(width 0.1524)
				(type default)
			)
			(layer "B.SilkS")
		)
		(fp_line
			(start 0.7874 -0.4064)
			(end -0.7874 -0.4064)
			(stroke
				(width 0.1524)
				(type default)
			)
			(layer "B.SilkS")
		)
		(fp_line
			(start 0.7874 0.4064)
			(end 0.7874 -0.4064)
			(stroke
				(width 0.1524)
				(type default)
			)
			(layer "B.SilkS")
		)
		(fp_line
			(start -0.67945 -0.3048)
			(end -0.67945 0.3048)
			(stroke
				(width 0.1)
				(type default)
			)
			(layer "B.Fab")
		)
		(fp_line
			(start -0.67945 0.3048)
			(end -0.120396 0.3048)
			(stroke
				(width 0.1)
				(type default)
			)
			(layer "B.Fab")
		)
		(fp_line
			(start -0.12065 -0.3048)
			(end -0.67945 -0.3048)
			(stroke
				(width 0.1)
				(type default)
			)
			(layer "B.Fab")
		)
		(fp_line
			(start -0.12065 -0.2794)
			(end -0.12065 -0.3048)
			(stroke
				(width 0.1)
				(type default)
			)
			(layer "B.Fab")
		)
		(fp_line
			(start -0.120396 0.2794)
			(end 0.12065 0.2794)
			(stroke
				(width 0.1)
				(type default)
			)
			(layer "B.Fab")
		)
		(fp_line
			(start -0.120396 0.3048)
			(end -0.120396 0.2794)
			(stroke
				(width 0.1)
				(type default)
			)
			(layer "B.Fab")
		)
		(fp_line
			(start 0.12065 -0.305054)
			(end 0.12065 -0.2794)
			(stroke
				(width 0.1)
				(type default)
			)
			(layer "B.Fab")
		)
		(fp_line
			(start 0.12065 -0.2794)
			(end -0.12065 -0.2794)
			(stroke
				(width 0.1)
				(type default)
			)
			(layer "B.Fab")
		)
		(fp_line
			(start 0.12065 0.2794)
			(end 0.12065 0.3048)
			(stroke
				(width 0.1)
				(type default)
			)
			(layer "B.Fab")
		)
		(fp_line
			(start 0.12065 0.3048)
			(end 0.67945 0.3048)
			(stroke
				(width 0.1)
				(type default)
			)
			(layer "B.Fab")
		)
		(fp_line
			(start 0.67945 -0.305054)
			(end 0.12065 -0.305054)
			(stroke
				(width 0.1)
				(type default)
			)
			(layer "B.Fab")
		)
		(fp_line
			(start 0.67945 0.3048)
			(end 0.67945 -0.305054)
			(stroke
				(width 0.1)
				(type default)
			)
			(layer "B.Fab")
		)
		(pad "1" smd circle
			(at 0.40005 0 180)
			(size 0 0)
			(layers "B.Cu" "B.Mask" "B.Paste")
			(net "P3V3_AUX")
		)
		(pad "2" smd circle
			(at -0.40005 0 180)
			(size 0 0)
			(layers "B.Cu" "B.Mask" "B.Paste")
			(net "GPU_FPGA_READY_ISO")
		)
	)
	(footprint ""
		(layer "B.Cu")
		(at 120.47855 -386.766562 90)
		(property "Reference" "C449"
			(at 0 0 90)
			(layer "B.SilkS")
			(hide yes)
			(effects
				(font
					(size 1.27 1.27)
				)
				(justify mirror)
			)
		)
		(property "Value" ""
			(at 0 0 90)
			(layer "B.Fab")
			(effects
				(font
					(size 1.27 1.27)
				)
				(justify mirror)
			)
		)
		(duplicate_pad_numbers_are_jumpers no)
		(fp_line
			(start 0.299974 -0.150114)
			(end -0.299974 -0.150114)
			(stroke
				(width 0.1)
				(type default)
			)
			(layer "B.Fab")
		)
		(fp_line
			(start -0.299974 -0.150114)
			(end -0.299974 0.150114)
			(stroke
				(width 0.1)
				(type default)
			)
			(layer "B.Fab")
		)
		(fp_line
			(start 0.299974 0.150114)
			(end 0.299974 -0.150114)
			(stroke
				(width 0.1)
				(type default)
			)
			(layer "B.Fab")
		)
		(fp_line
			(start -0.299974 0.150114)
			(end 0.299974 0.150114)
			(stroke
				(width 0.1)
				(type default)
			)
			(layer "B.Fab")
		)
		(pad "1" smd rect
			(at 0.2667 0 270)
			(size 0.3048 0.381)
			(layers "B.Cu" "B.Mask" "B.Paste")
			(net "P0V9_CPU1_RT_2D")
		)
		(pad "2" smd rect
			(at -0.2667 0 270)
			(size 0.3048 0.381)
			(layers "B.Cu" "B.Mask" "B.Paste")
			(net "GND")
		)
	)
)
